(kicad_pcb
	(version 20241229)
	(generator "pcbnew")
	(generator_version "9.0")
	(general
		(thickness 1.599998)
		(legacy_teardrops no)
	)
	(paper "A4")
	(title_block
		(date "2023-02-12")
		(rev "1.1.5")
		(comment 9 "footprints 415-421 of 473")
	)
	(layers
		(0 "F.Cu" signal)
		(4 "In1.Cu" power "In1.GND")
		(6 "In2.Cu" signal)
		(8 "In3.Cu" power "In3.GND")
		(10 "In4.Cu" power "In4.VCC")
		(12 "In5.Cu" signal)
		(14 "In6.Cu" power "In6.VCC")
		(2 "B.Cu" signal)
		(9 "F.Adhes" user "F.Adhesive")
		(11 "B.Adhes" user "B.Adhesive")
		(13 "F.Paste" user)
		(15 "B.Paste" user)
		(5 "F.SilkS" user "F.Silkscreen")
		(7 "B.SilkS" user "B.Silkscreen")
		(1 "F.Mask" user)
		(3 "B.Mask" user)
		(17 "Dwgs.User" user "User.Drawings")
		(19 "Cmts.User" user "User.Comments")
		(21 "Eco1.User" user "User.Eco1")
		(23 "Eco2.User" user "User.Eco2")
		(25 "Edge.Cuts" user)
		(27 "Margin" user)
		(31 "F.CrtYd" user "F.Courtyard")
		(29 "B.CrtYd" user "B.Courtyard")
		(35 "F.Fab" user)
		(33 "B.Fab" user)
	)
	(footprint "antmicro-footprints:R_0402_1005Metric"
		(layer "B.Cu")
		(at 195.686328 96.220008 90)
		(descr "Resistor SMD 0402")
		(tags "resistor SMD 0402")
		(property "Reference" "R79"
			(at 3.020008 0.513672 270)
			(layer "B.SilkS")
			(effects
				(font
					(size 0.7 0.7)
					(thickness 0.15)
				)
				(justify left bottom mirror)
			)
		)
		(property "Value" "R_10k2_0402"
			(at 0 -1.4 270)
			(layer "B.Fab")
			(effects
				(font
					(size 0.7 0.7)
					(thickness 0.15)
				)
				(justify left bottom mirror)
			)
		)
		(property "Description" "10k2 resistor in 0402 package with 1% tolerance"
			(at 0 0 90)
			(layer "F.Fab")
			(hide yes)
			(effects
				(font
					(size 1.27 1.27)
					(thickness 0.15)
				)
			)
		)
		(property "Author" "Antmicro"
			(at 291.906336 -99.46632 0)
			(layer "B.Fab")
			(hide yes)
			(effects
				(font
					(size 1 1)
					(thickness 0.15)
				)
				(justify mirror)
			)
		)
		(property "License" "Apache-2.0"
			(at 291.906336 -99.46632 0)
			(layer "B.Fab")
			(hide yes)
			(effects
				(font
					(size 1 1)
					(thickness 0.15)
				)
				(justify mirror)
			)
		)
		(property "MPN" "CR0402-FX-1022GLF"
			(at 291.906336 -99.46632 0)
			(layer "B.Fab")
			(hide yes)
			(effects
				(font
					(size 1 1)
					(thickness 0.15)
				)
				(justify mirror)
			)
		)
		(property "Manufacturer" "Bourns"
			(at 291.906336 -99.46632 0)
			(layer "B.Fab")
			(hide yes)
			(effects
				(font
					(size 1 1)
					(thickness 0.15)
				)
				(justify mirror)
			)
		)
		(property "Tolerance" "1%"
			(at 291.906336 -99.46632 0)
			(layer "B.Fab")
			(hide yes)
			(effects
				(font
					(size 1 1)
					(thickness 0.15)
				)
				(justify mirror)
			)
		)
		(property "Val" "10k2"
			(at 291.906336 -99.46632 0)
			(layer "B.Fab")
			(hide yes)
			(effects
				(font
					(size 1 1)
					(thickness 0.15)
				)
				(justify mirror)
			)
		)
		(sheetname "Ethernet")
		(sheetfile "ethernet.kicad_sch")
		(attr exclude_from_pos_files exclude_from_bom dnp)
		(fp_rect
			(start -0.93 0.47)
			(end 0.93 -0.47)
			(stroke
				(width 0.05)
				(type solid)
			)
			(fill no)
			(layer "B.CrtYd")
		)
		(fp_rect
			(start -0.5 0.25)
			(end 0.5 -0.25)
			(stroke
				(width 0.15)
				(type solid)
			)
			(fill no)
			(layer "B.Fab")
		)
		(pad "1" smd roundrect
			(at -0.485 0 90)
			(size 0.59 0.64)
			(layers "B.Cu" "B.Mask" "B.Paste")
			(roundrect_rratio 0.25)
			(net 36 "ETH_RX_CLK")
			(pintype "passive")
		)
		(pad "2" smd roundrect
			(at 0.485 0 90)
			(size 0.59 0.64)
			(layers "B.Cu" "B.Mask" "B.Paste")
			(roundrect_rratio 0.25)
			(net 459 "3V3_SYS")
			(pintype "passive")
		)
	)
	(footprint "antmicro-footprints:R_0402_1005Metric"
		(layer "B.Cu")
		(at 198.376328 103.390008 -90)
		(descr "Resistor SMD 0402")
		(tags "resistor SMD 0402")
		(property "Reference" "R80"
			(at -1.090008 -1.223672 90)
			(layer "B.SilkS")
			(effects
				(font
					(size 0.7 0.7)
					(thickness 0.15)
				)
				(justify left bottom mirror)
			)
		)
		(property "Value" "R_10k2_0402"
			(at 0 -1.4 90)
			(layer "B.Fab")
			(effects
				(font
					(size 0.7 0.7)
					(thickness 0.15)
				)
				(justify left bottom mirror)
			)
		)
		(property "Description" "10k2 resistor in 0402 package with 1% tolerance"
			(at 0 0 270)
			(layer "F.Fab")
			(hide yes)
			(effects
				(font
					(size 1.27 1.27)
					(thickness 0.15)
				)
			)
		)
		(property "Author" "Antmicro"
			(at 94.98632 301.766336 0)
			(layer "B.Fab")
			(hide yes)
			(effects
				(font
					(size 1 1)
					(thickness 0.15)
				)
				(justify mirror)
			)
		)
		(property "License" "Apache-2.0"
			(at 94.98632 301.766336 0)
			(layer "B.Fab")
			(hide yes)
			(effects
				(font
					(size 1 1)
					(thickness 0.15)
				)
				(justify mirror)
			)
		)
		(property "MPN" "CR0402-FX-1022GLF"
			(at 94.98632 301.766336 0)
			(layer "B.Fab")
			(hide yes)
			(effects
				(font
					(size 1 1)
					(thickness 0.15)
				)
				(justify mirror)
			)
		)
		(property "Manufacturer" "Bourns"
			(at 94.98632 301.766336 0)
			(layer "B.Fab")
			(hide yes)
			(effects
				(font
					(size 1 1)
					(thickness 0.15)
				)
				(justify mirror)
			)
		)
		(property "Tolerance" "1%"
			(at 94.98632 301.766336 0)
			(layer "B.Fab")
			(hide yes)
			(effects
				(font
					(size 1 1)
					(thickness 0.15)
				)
				(justify mirror)
			)
		)
		(property "Val" "10k2"
			(at 94.98632 301.766336 0)
			(layer "B.Fab")
			(hide yes)
			(effects
				(font
					(size 1 1)
					(thickness 0.15)
				)
				(justify mirror)
			)
		)
		(sheetname "Ethernet")
		(sheetfile "ethernet.kicad_sch")
		(attr smd)
		(fp_rect
			(start -0.93 0.47)
			(end 0.93 -0.47)
			(stroke
				(width 0.05)
				(type solid)
			)
			(fill no)
			(layer "B.CrtYd")
		)
		(fp_rect
			(start -0.5 0.25)
			(end 0.5 -0.25)
			(stroke
				(width 0.15)
				(type solid)
			)
			(fill no)
			(layer "B.Fab")
		)
		(pad "1" smd roundrect
			(at -0.485 0 270)
			(size 0.59 0.64)
			(layers "B.Cu" "B.Mask" "B.Paste")
			(roundrect_rratio 0.25)
			(net 26 "ETH_REF_CLK")
			(pintype "passive")
		)
		(pad "2" smd roundrect
			(at 0.485 0 270)
			(size 0.59 0.64)
			(layers "B.Cu" "B.Mask" "B.Paste")
			(roundrect_rratio 0.25)
			(net 459 "3V3_SYS")
			(pintype "passive")
		)
	)
	(footprint "antmicro-footprints:R_0402_1005Metric"
		(layer "B.Cu")
		(at 198.771328 97.445008 -90)
		(descr "Resistor SMD 0402")
		(tags "resistor SMD 0402")
		(property "Reference" "R85"
			(at -1.045008 -1.328672 90)
			(layer "B.SilkS")
			(effects
				(font
					(size 0.7 0.7)
					(thickness 0.15)
				)
				(justify left bottom mirror)
			)
		)
		(property "Value" "R_2k2_0402"
			(at 0 -1.4 90)
			(layer "B.Fab")
			(effects
				(font
					(size 0.7 0.7)
					(thickness 0.15)
				)
				(justify left bottom mirror)
			)
		)
		(property "Description" "2k2 resistor in 0402 package with 1% tolerance"
			(at 0 0 270)
			(layer "F.Fab")
			(hide yes)
			(effects
				(font
					(size 1.27 1.27)
					(thickness 0.15)
				)
			)
		)
		(property "Author" "Antmicro"
			(at 101.32632 296.216336 0)
			(layer "B.Fab")
			(hide yes)
			(effects
				(font
					(size 1 1)
					(thickness 0.15)
				)
				(justify mirror)
			)
		)
		(property "License" "Apache-2.0"
			(at 101.32632 296.216336 0)
			(layer "B.Fab")
			(hide yes)
			(effects
				(font
					(size 1 1)
					(thickness 0.15)
				)
				(justify mirror)
			)
		)
		(property "MPN" "CR0402-FX-2201GLF"
			(at 101.32632 296.216336 0)
			(layer "B.Fab")
			(hide yes)
			(effects
				(font
					(size 1 1)
					(thickness 0.15)
				)
				(justify mirror)
			)
		)
		(property "Manufacturer" "Bourns"
			(at 101.32632 296.216336 0)
			(layer "B.Fab")
			(hide yes)
			(effects
				(font
					(size 1 1)
					(thickness 0.15)
				)
				(justify mirror)
			)
		)
		(property "Tolerance" "1%"
			(at 101.32632 296.216336 0)
			(layer "B.Fab")
			(hide yes)
			(effects
				(font
					(size 1 1)
					(thickness 0.15)
				)
				(justify mirror)
			)
		)
		(property "Val" "2k2"
			(at 101.32632 296.216336 0)
			(layer "B.Fab")
			(hide yes)
			(effects
				(font
					(size 1 1)
					(thickness 0.15)
				)
				(justify mirror)
			)
		)
		(sheetname "Ethernet")
		(sheetfile "ethernet.kicad_sch")
		(attr smd)
		(fp_rect
			(start -0.93 0.47)
			(end 0.93 -0.47)
			(stroke
				(width 0.05)
				(type solid)
			)
			(fill no)
			(layer "B.CrtYd")
		)
		(fp_rect
			(start -0.5 0.25)
			(end 0.5 -0.25)
			(stroke
				(width 0.15)
				(type solid)
			)
			(fill no)
			(layer "B.Fab")
		)
		(pad "1" smd roundrect
			(at -0.485 0 270)
			(size 0.59 0.64)
			(layers "B.Cu" "B.Mask" "B.Paste")
			(roundrect_rratio 0.25)
			(net 22 "ETH_RXD0")
			(pintype "passive")
		)
		(pad "2" smd roundrect
			(at 0.485 0 270)
			(size 0.59 0.64)
			(layers "B.Cu" "B.Mask" "B.Paste")
			(roundrect_rratio 0.25)
			(net 5 "GND")
			(pintype "passive")
		)
	)
	(footprint "antmicro-footprints:R_0402_1005Metric"
		(layer "B.Cu")
		(at 195.886328 99.520008)
		(descr "Resistor SMD 0402")
		(tags "resistor SMD 0402")
		(property "Reference" "R83"
			(at 1.013672 1.379992 180)
			(layer "B.SilkS")
			(effects
				(font
					(size 0.7 0.7)
					(thickness 0.15)
				)
				(justify left bottom mirror)
			)
		)
		(property "Value" "R_1k_0402"
			(at 0 -1.4 180)
			(layer "B.Fab")
			(effects
				(font
					(size 0.7 0.7)
					(thickness 0.15)
				)
				(justify left bottom mirror)
			)
		)
		(property "Description" "1k resistor in 0402 package with 1% tolerance"
			(at 0 0 0)
			(layer "F.Fab")
			(hide yes)
			(effects
				(font
					(size 1.27 1.27)
					(thickness 0.15)
				)
			)
		)
		(property "Author" "Antmicro"
			(at 0 0 0)
			(layer "B.Fab")
			(hide yes)
			(effects
				(font
					(size 1 1)
					(thickness 0.15)
				)
				(justify mirror)
			)
		)
		(property "License" "Apache-2.0"
			(at 0 0 0)
			(layer "B.Fab")
			(hide yes)
			(effects
				(font
					(size 1 1)
					(thickness 0.15)
				)
				(justify mirror)
			)
		)
		(property "MPN" "CR0402-FX-1001GLF"
			(at 0 0 0)
			(layer "B.Fab")
			(hide yes)
			(effects
				(font
					(size 1 1)
					(thickness 0.15)
				)
				(justify mirror)
			)
		)
		(property "Manufacturer" "Bourns"
			(at 0 0 0)
			(layer "B.Fab")
			(hide yes)
			(effects
				(font
					(size 1 1)
					(thickness 0.15)
				)
				(justify mirror)
			)
		)
		(property "Tolerance" "1%"
			(at 0 0 0)
			(layer "B.Fab")
			(hide yes)
			(effects
				(font
					(size 1 1)
					(thickness 0.15)
				)
				(justify mirror)
			)
		)
		(property "Val" "1k"
			(at 0 0 0)
			(layer "B.Fab")
			(hide yes)
			(effects
				(font
					(size 1 1)
					(thickness 0.15)
				)
				(justify mirror)
			)
		)
		(sheetname "Ethernet")
		(sheetfile "ethernet.kicad_sch")
		(attr smd)
		(fp_rect
			(start -0.93 0.47)
			(end 0.93 -0.47)
			(stroke
				(width 0.05)
				(type solid)
			)
			(fill no)
			(layer "B.CrtYd")
		)
		(fp_rect
			(start -0.5 0.25)
			(end 0.5 -0.25)
			(stroke
				(width 0.15)
				(type solid)
			)
			(fill no)
			(layer "B.Fab")
		)
		(pad "1" smd roundrect
			(at -0.485 0)
			(size 0.59 0.64)
			(layers "B.Cu" "B.Mask" "B.Paste")
			(roundrect_rratio 0.25)
			(net 25 "ETH_MDIO")
			(pintype "passive")
		)
		(pad "2" smd roundrect
			(at 0.485 0)
			(size 0.59 0.64)
			(layers "B.Cu" "B.Mask" "B.Paste")
			(roundrect_rratio 0.25)
			(net 459 "3V3_SYS")
			(pintype "passive")
		)
	)
	(footprint "antmicro-footprints:R_0402_1005Metric"
		(layer "B.Cu")
		(at 196.886328 103.320008)
		(descr "Resistor SMD 0402")
		(tags "resistor SMD 0402")
		(property "Reference" "R84"
			(at 1.013672 1.279992 180)
			(layer "B.SilkS")
			(effects
				(font
					(size 0.7 0.7)
					(thickness 0.15)
				)
				(justify left bottom mirror)
			)
		)
		(property "Value" "R_10k2_0402"
			(at 0 -1.4 180)
			(layer "B.Fab")
			(effects
				(font
					(size 0.7 0.7)
					(thickness 0.15)
				)
				(justify left bottom mirror)
			)
		)
		(property "Description" "10k2 resistor in 0402 package with 1% tolerance"
			(at 0 0 0)
			(layer "F.Fab")
			(hide yes)
			(effects
				(font
					(size 1.27 1.27)
					(thickness 0.15)
				)
			)
		)
		(property "Author" "Antmicro"
			(at 0 0 0)
			(layer "B.Fab")
			(hide yes)
			(effects
				(font
					(size 1 1)
					(thickness 0.15)
				)
				(justify mirror)
			)
		)
		(property "License" "Apache-2.0"
			(at 0 0 0)
			(layer "B.Fab")
			(hide yes)
			(effects
				(font
					(size 1 1)
					(thickness 0.15)
				)
				(justify mirror)
			)
		)
		(property "MPN" "CR0402-FX-1022GLF"
			(at 0 0 0)
			(layer "B.Fab")
			(hide yes)
			(effects
				(font
					(size 1 1)
					(thickness 0.15)
				)
				(justify mirror)
			)
		)
		(property "Manufacturer" "Bourns"
			(at 0 0 0)
			(layer "B.Fab")
			(hide yes)
			(effects
				(font
					(size 1 1)
					(thickness 0.15)
				)
				(justify mirror)
			)
		)
		(property "Tolerance" "1%"
			(at 0 0 0)
			(layer "B.Fab")
			(hide yes)
			(effects
				(font
					(size 1 1)
					(thickness 0.15)
				)
				(justify mirror)
			)
		)
		(property "Val" "10k2"
			(at 0 0 0)
			(layer "B.Fab")
			(hide yes)
			(effects
				(font
					(size 1 1)
					(thickness 0.15)
				)
				(justify mirror)
			)
		)
		(sheetname "Ethernet")
		(sheetfile "ethernet.kicad_sch")
		(attr smd)
		(fp_rect
			(start -0.93 0.47)
			(end 0.93 -0.47)
			(stroke
				(width 0.05)
				(type solid)
			)
			(fill no)
			(layer "B.CrtYd")
		)
		(fp_rect
			(start -0.5 0.25)
			(end 0.5 -0.25)
			(stroke
				(width 0.15)
				(type solid)
			)
			(fill no)
			(layer "B.Fab")
		)
		(pad "1" smd roundrect
			(at -0.485 0)
			(size 0.59 0.64)
			(layers "B.Cu" "B.Mask" "B.Paste")
			(roundrect_rratio 0.25)
			(net 24 "ETH_RSTN")
			(pintype "passive")
		)
		(pad "2" smd roundrect
			(at 0.485 0)
			(size 0.59 0.64)
			(layers "B.Cu" "B.Mask" "B.Paste")
			(roundrect_rratio 0.25)
			(net 459 "3V3_SYS")
			(pintype "passive")
		)
	)
	(footprint "antmicro-footprints:R_0402_1005Metric"
		(layer "B.Cu")
		(at 208.786328 105.020008)
		(descr "Resistor SMD 0402")
		(tags "resistor SMD 0402")
		(property "Reference" "R81"
			(at 3.013672 0.379992 180)
			(layer "B.SilkS")
			(effects
				(font
					(size 0.7 0.7)
					(thickness 0.15)
				)
				(justify left bottom mirror)
			)
		)
		(property "Value" "R_10k2_0402"
			(at 0 -1.4 180)
			(layer "B.Fab")
			(effects
				(font
					(size 0.7 0.7)
					(thickness 0.15)
				)
				(justify left bottom mirror)
			)
		)
		(property "Description" "10k2 resistor in 0402 package with 1% tolerance"
			(at 0 0 0)
			(layer "F.Fab")
			(hide yes)
			(effects
				(font
					(size 1.27 1.27)
					(thickness 0.15)
				)
			)
		)
		(property "Author" "Antmicro"
			(at 0 0 0)
			(layer "B.Fab")
			(hide yes)
			(effects
				(font
					(size 1 1)
					(thickness 0.15)
				)
				(justify mirror)
			)
		)
		(property "License" "Apache-2.0"
			(at 0 0 0)
			(layer "B.Fab")
			(hide yes)
			(effects
				(font
					(size 1 1)
					(thickness 0.15)
				)
				(justify mirror)
			)
		)
		(property "MPN" "CR0402-FX-1022GLF"
			(at 0 0 0)
			(layer "B.Fab")
			(hide yes)
			(effects
				(font
					(size 1 1)
					(thickness 0.15)
				)
				(justify mirror)
			)
		)
		(property "Manufacturer" "Bourns"
			(at 0 0 0)
			(layer "B.Fab")
			(hide yes)
			(effects
				(font
					(size 1 1)
					(thickness 0.15)
				)
				(justify mirror)
			)
		)
		(property "Tolerance" "1%"
			(at 0 0 0)
			(layer "B.Fab")
			(hide yes)
			(effects
				(font
					(size 1 1)
					(thickness 0.15)
				)
				(justify mirror)
			)
		)
		(property "Val" "10k2"
			(at 0 0 0)
			(layer "B.Fab")
			(hide yes)
			(effects
				(font
					(size 1 1)
					(thickness 0.15)
				)
				(justify mirror)
			)
		)
		(sheetname "Ethernet")
		(sheetfile "ethernet.kicad_sch")
		(attr smd)
		(fp_rect
			(start -0.93 0.47)
			(end 0.93 -0.47)
			(stroke
				(width 0.05)
				(type solid)
			)
			(fill no)
			(layer "B.CrtYd")
		)
		(fp_rect
			(start -0.5 0.25)
			(end 0.5 -0.25)
			(stroke
				(width 0.15)
				(type solid)
			)
			(fill no)
			(layer "B.Fab")
		)
		(pad "1" smd roundrect
			(at -0.485 0)
			(size 0.59 0.64)
			(layers "B.Cu" "B.Mask" "B.Paste")
			(roundrect_rratio 0.25)
			(net 13 "LED_SPD")
			(pintype "passive")
		)
		(pad "2" smd roundrect
			(at 0.485 0)
			(size 0.59 0.64)
			(layers "B.Cu" "B.Mask" "B.Paste")
			(roundrect_rratio 0.25)
			(net 459 "3V3_SYS")
			(pintype "passive")
		)
	)
	(footprint "antmicro-footprints:C_0402_1005Metric"
		(layer "B.Cu")
		(at 199.086328 108.789306 -90)
		(descr "Capacitor SMD 0402")
		(tags "capacitor SMD 0402")
		(property "Reference" "C99"
			(at 0.810694 -0.413672 90)
			(layer "B.SilkS")
			(effects
				(font
					(size 0.7 0.7)
					(thickness 0.15)
				)
				(justify left bottom mirror)
			)
		)
		(property "Value" "C_4u7_0402"
			(at 0 -1.4 90)
			(layer "B.Fab")
			(effects
				(font
					(size 0.7 0.7)
					(thickness 0.15)
				)
				(justify left bottom mirror)
			)
		)
		(property "Description" " "
			(at 0 0 270)
			(layer "F.Fab")
			(hide yes)
			(effects
				(font
					(size 1.27 1.27)
					(thickness 0.15)
				)
			)
		)
		(property "Author" "Antmicro"
			(at 90.297022 307.875634 0)
			(layer "B.Fab")
			(hide yes)
			(effects
				(font
					(size 1 1)
					(thickness 0.15)
				)
				(justify mirror)
			)
		)
		(property "Dielectric" ""
			(at 90.297022 307.875634 0)
			(layer "B.Fab")
			(hide yes)
			(effects
				(font
					(size 1 1)
					(thickness 0.15)
				)
				(justify mirror)
			)
		)
		(property "License" "Apache-2.0"
			(at 90.297022 307.875634 0)
			(layer "B.Fab")
			(hide yes)
			(effects
				(font
					(size 1 1)
					(thickness 0.15)
				)
				(justify mirror)
			)
		)
		(property "MPN" "GRM155R61A475MEAAD"
			(at 90.297022 307.875634 0)
			(layer "B.Fab")
			(hide yes)
			(effects
				(font
					(size 1 1)
					(thickness 0.15)
				)
				(justify mirror)
			)
		)
		(property "Manufacturer" "Murata"
			(at 90.297022 307.875634 0)
			(layer "B.Fab")
			(hide yes)
			(effects
				(font
					(size 1 1)
					(thickness 0.15)
				)
				(justify mirror)
			)
		)
		(property "Val" "4u7"
			(at 90.297022 307.875634 0)
			(layer "B.Fab")
			(hide yes)
			(effects
				(font
					(size 1 1)
					(thickness 0.15)
				)
				(justify mirror)
			)
		)
		(property "Voltage" ""
			(at 90.297022 307.875634 0)
			(layer "B.Fab")
			(hide yes)
			(effects
				(font
					(size 1 1)
					(thickness 0.15)
				)
				(justify mirror)
			)
		)
		(sheetname "Ethernet")
		(sheetfile "ethernet.kicad_sch")
		(attr smd)
		(fp_rect
			(start -0.94 0.47)
			(end 0.94 -0.47)
			(stroke
				(width 0.05)
				(type solid)
			)
			(fill no)
			(layer "B.CrtYd")
		)
		(fp_rect
			(start -0.499 0.249)
			(end 0.499 -0.249)
			(stroke
				(width 0.15)
				(type solid)
			)
			(fill no)
			(layer "B.Fab")
		)
		(pad "1" smd roundrect
			(at -0.484 0 270)
			(size 0.59 0.64)
			(layers "B.Cu" "B.Mask" "B.Paste")
			(roundrect_rratio 0.25)
			(net 529 "/Ethernet/AVDDL")
			(pintype "passive")
		)
		(pad "2" smd roundrect
			(at 0.484 0 270)
			(size 0.59 0.64)
			(layers "B.Cu" "B.Mask" "B.Paste")
			(roundrect_rratio 0.25)
			(net 5 "GND")
			(pintype "passive")
		)
	)
)
